# T6G (Grand Teton) — schematic netlist excerpt (pin names and nets, part order shuffled) for the footprints in the layout excerpt that follows; sources: Cadence DE-HDL packaged netlist, KiCad conversion of 04192023_DAF0TMB3IC0_F0TG_MB_C_brd_V02_OCP.brd

PC8011  Q_CAP  22UF 16V 20% X6S  pkg C0805  page 215 : A = SW_P12V_AUX_PVDDCR_SOC_P1_FLT ; B = GND
R521  Q_RES  2.2K 5% CHIP  pkg 0402LF  page 54 : A = CPU1_SA1 ; B = GND
R38  Q_RES  0 5% CHIP  pkg 0402LF  page 131 : A = OCP_SFF_MAIN_PWR_EN ; B = OCP_SFF_MAIN_PWR_EN_R

(kicad_pcb
	(version 20260206)
	(generator "pcbnew")
	(generator_version "10.0")
	(general
		(thickness 1.6)
		(legacy_teardrops no)
	)
	(paper "A4")
	(title_block
		(title "04192023_DAF0TMB3IC0_F0TG_MB_C_brd_V02_OCP.brd")
		(comment 1 "Grand Teton / footprints 5861-5863 of 8354")
	)
	(layers
		(0 "F.Cu" signal "TOP")
		(4 "In1.Cu" signal "GND")
		(6 "In2.Cu" signal "IN1")
		(8 "In3.Cu" signal "GND1")
		(10 "In4.Cu" signal "IN2")
		(12 "In5.Cu" signal "GND2")
		(14 "In6.Cu" signal "IN3")
		(16 "In7.Cu" signal "GND3")
		(18 "In8.Cu" signal "VCC")
		(20 "In9.Cu" signal "VCC1")
		(22 "In10.Cu" signal "GND4")
		(24 "In11.Cu" signal "IN4")
		(26 "In12.Cu" signal "GND5")
		(28 "In13.Cu" signal "IN5")
		(30 "In14.Cu" signal "GND6")
		(32 "In15.Cu" signal "IN6")
		(34 "In16.Cu" signal "GND7")
		(2 "B.Cu" signal "BOTTOM")
		(9 "F.Adhes" user "F.Adhesive")
		(11 "B.Adhes" user "B.Adhesive")
		(13 "F.Paste" user "Package Geometry/Pastemask Top")
		(15 "B.Paste" user "Package Geometry/Pastemask Bottom")
		(5 "F.SilkS" user "Ref Des/Silkscreen Top")
		(7 "B.SilkS" user "Ref Des/Silkscreen Bottom")
		(1 "F.Mask" user "Board Geometry/Soldermask Top")
		(3 "B.Mask" user "Board Geometry/Soldermask Bottom")
		(17 "Dwgs.User" user "User.Drawings")
		(19 "Cmts.User" user "User.Comments")
		(21 "Eco1.User" user "User.Eco1")
		(23 "Eco2.User" user "User.Eco2")
		(25 "Edge.Cuts" user "Board Geometry/Outline")
		(27 "Margin" user)
		(31 "F.CrtYd" user "Package Geometry/Place Bound Top")
		(29 "B.CrtYd" user "Package Geometry/Place Bound Bottom")
		(35 "F.Fab" user "Ref Des/Assembly Top")
		(33 "B.Fab" user "Ref Des/Assembly Bottom")
	)
	(footprint ""
		(layer "B.Cu")
		(at 454.02246 -11.705844)
		(property "Reference" "R38"
			(at 0 0 0)
			(layer "B.SilkS")
			(hide yes)
			(effects
				(font
					(size 1.27 1.27)
				)
				(justify mirror)
			)
		)
		(property "Value" ""
			(at 0 0 0)
			(layer "B.Fab")
			(effects
				(font
					(size 1.27 1.27)
				)
				(justify mirror)
			)
		)
		(duplicate_pad_numbers_are_jumpers no)
		(fp_line
			(start -0.7874 -0.4064)
			(end -0.7874 0.4064)
			(stroke
				(width 0.1524)
				(type default)
			)
			(layer "B.SilkS")
		)
		(fp_line
			(start -0.7874 0.4064)
			(end 0.7874 0.4064)
			(stroke
				(width 0.1524)
				(type default)
			)
			(layer "B.SilkS")
		)
		(fp_line
			(start 0.7874 -0.4064)
			(end -0.7874 -0.4064)
			(stroke
				(width 0.1524)
				(type default)
			)
			(layer "B.SilkS")
		)
		(fp_line
			(start 0.7874 0.4064)
			(end 0.7874 -0.4064)
			(stroke
				(width 0.1524)
				(type default)
			)
			(layer "B.SilkS")
		)
		(fp_line
			(start -0.67945 -0.3048)
			(end -0.67945 0.3048)
			(stroke
				(width 0.1)
				(type default)
			)
			(layer "B.Fab")
		)
		(fp_line
			(start -0.67945 0.3048)
			(end -0.120396 0.3048)
			(stroke
				(width 0.1)
				(type default)
			)
			(layer "B.Fab")
		)
		(fp_line
			(start -0.12065 -0.3048)
			(end -0.67945 -0.3048)
			(stroke
				(width 0.1)
				(type default)
			)
			(layer "B.Fab")
		)
		(fp_line
			(start -0.12065 -0.2794)
			(end -0.12065 -0.3048)
			(stroke
				(width 0.1)
				(type default)
			)
			(layer "B.Fab")
		)
		(fp_line
			(start -0.120396 0.2794)
			(end 0.12065 0.2794)
			(stroke
				(width 0.1)
				(type default)
			)
			(layer "B.Fab")
		)
		(fp_line
			(start -0.120396 0.3048)
			(end -0.120396 0.2794)
			(stroke
				(width 0.1)
				(type default)
			)
			(layer "B.Fab")
		)
		(fp_line
			(start 0.12065 -0.305054)
			(end 0.12065 -0.2794)
			(stroke
				(width 0.1)
				(type default)
			)
			(layer "B.Fab")
		)
		(fp_line
			(start 0.12065 -0.2794)
			(end -0.12065 -0.2794)
			(stroke
				(width 0.1)
				(type default)
			)
			(layer "B.Fab")
		)
		(fp_line
			(start 0.12065 0.2794)
			(end 0.12065 0.3048)
			(stroke
				(width 0.1)
				(type default)
			)
			(layer "B.Fab")
		)
		(fp_line
			(start 0.12065 0.3048)
			(end 0.67945 0.3048)
			(stroke
				(width 0.1)
				(type default)
			)
			(layer "B.Fab")
		)
		(fp_line
			(start 0.67945 -0.305054)
			(end 0.12065 -0.305054)
			(stroke
				(width 0.1)
				(type default)
			)
			(layer "B.Fab")
		)
		(fp_line
			(start 0.67945 0.3048)
			(end 0.67945 -0.305054)
			(stroke
				(width 0.1)
				(type default)
			)
			(layer "B.Fab")
		)
		(pad "1" smd circle
			(at 0.40005 0 180)
			(size 0 0)
			(layers "B.Cu" "B.Mask" "B.Paste")
			(net "OCP_SFF_MAIN_PWR_EN")
		)
		(pad "2" smd circle
			(at -0.40005 0 180)
			(size 0 0)
			(layers "B.Cu" "B.Mask" "B.Paste")
			(net "OCP_SFF_MAIN_PWR_EN_R")
		)
	)
	(footprint ""
		(layer "B.Cu")
		(at 91.493594 -301.716948 180)
		(property "Reference" "R521"
			(at 0 0 0)
			(layer "B.SilkS")
			(hide yes)
			(effects
				(font
					(size 1.27 1.27)
				)
				(justify mirror)
			)
		)
		(property "Value" ""
			(at 0 0 0)
			(layer "B.Fab")
			(effects
				(font
					(size 1.27 1.27)
				)
				(justify mirror)
			)
		)
		(duplicate_pad_numbers_are_jumpers no)
		(fp_line
			(start 0.7874 0.4064)
			(end 0.7874 -0.4064)
			(stroke
				(width 0.1524)
				(type default)
			)
			(layer "B.SilkS")
		)
		(fp_line
			(start 0.7874 -0.4064)
			(end -0.7874 -0.4064)
			(stroke
				(width 0.1524)
				(type default)
			)
			(layer "B.SilkS")
		)
		(fp_line
			(start -0.7874 0.4064)
			(end 0.7874 0.4064)
			(stroke
				(width 0.1524)
				(type default)
			)
			(layer "B.SilkS")
		)
		(fp_line
			(start -0.7874 -0.4064)
			(end -0.7874 0.4064)
			(stroke
				(width 0.1524)
				(type default)
			)
			(layer "B.SilkS")
		)
		(fp_line
			(start 0.67945 0.3048)
			(end 0.67945 -0.305054)
			(stroke
				(width 0.1)
				(type default)
			)
			(layer "B.Fab")
		)
		(fp_line
			(start 0.67945 -0.305054)
			(end 0.12065 -0.305054)
			(stroke
				(width 0.1)
				(type default)
			)
			(layer "B.Fab")
		)
		(fp_line
			(start 0.12065 0.3048)
			(end 0.67945 0.3048)
			(stroke
				(width 0.1)
				(type default)
			)
			(layer "B.Fab")
		)
		(fp_line
			(start 0.12065 0.2794)
			(end 0.12065 0.3048)
			(stroke
				(width 0.1)
				(type default)
			)
			(layer "B.Fab")
		)
		(fp_line
			(start 0.12065 -0.2794)
			(end -0.12065 -0.2794)
			(stroke
				(width 0.1)
				(type default)
			)
			(layer "B.Fab")
		)
		(fp_line
			(start 0.12065 -0.305054)
			(end 0.12065 -0.2794)
			(stroke
				(width 0.1)
				(type default)
			)
			(layer "B.Fab")
		)
		(fp_line
			(start -0.120396 0.3048)
			(end -0.120396 0.2794)
			(stroke
				(width 0.1)
				(type default)
			)
			(layer "B.Fab")
		)
		(fp_line
			(start -0.120396 0.2794)
			(end 0.12065 0.2794)
			(stroke
				(width 0.1)
				(type default)
			)
			(layer "B.Fab")
		)
		(fp_line
			(start -0.12065 -0.2794)
			(end -0.12065 -0.3048)
			(stroke
				(width 0.1)
				(type default)
			)
			(layer "B.Fab")
		)
		(fp_line
			(start -0.12065 -0.3048)
			(end -0.67945 -0.3048)
			(stroke
				(width 0.1)
				(type default)
			)
			(layer "B.Fab")
		)
		(fp_line
			(start -0.67945 0.3048)
			(end -0.120396 0.3048)
			(stroke
				(width 0.1)
				(type default)
			)
			(layer "B.Fab")
		)
		(fp_line
			(start -0.67945 -0.3048)
			(end -0.67945 0.3048)
			(stroke
				(width 0.1)
				(type default)
			)
			(layer "B.Fab")
		)
		(pad "1" smd circle
			(at 0.40005 0)
			(size 0 0)
			(layers "B.Cu" "B.Mask" "B.Paste")
			(net "CPU1_SA1")
		)
		(pad "2" smd circle
			(at -0.40005 0)
			(size 0 0)
			(layers "B.Cu" "B.Mask" "B.Paste")
			(net "GND")
		)
	)
	(footprint ""
		(layer "B.Cu")
		(at 125.800866 -156.378148 -90)
		(property "Reference" "PC8011"
			(at 0 0 90)
			(layer "B.SilkS")
			(hide yes)
			(effects
				(font
					(size 1.27 1.27)
				)
				(justify mirror)
			)
		)
		(property "Value" ""
			(at 0 0 90)
			(layer "B.Fab")
			(effects
				(font
					(size 1.27 1.27)
				)
				(justify mirror)
			)
		)
		(duplicate_pad_numbers_are_jumpers no)
		(fp_line
			(start -1.524 0.762)
			(end 1.524 0.762)
			(stroke
				(width 0.1524)
				(type default)
			)
			(layer "B.SilkS")
		)
		(fp_line
			(start 1.524 0.762)
			(end 1.524 -0.762)
			(stroke
				(width 0.1524)
				(type default)
			)
			(layer "B.SilkS")
		)
		(fp_line
			(start -1.524 -0.762)
			(end -1.524 0.762)
			(stroke
				(width 0.1524)
				(type default)
			)
			(layer "B.SilkS")
		)
		(fp_line
			(start 1.524 -0.762)
			(end -1.524 -0.762)
			(stroke
				(width 0.1524)
				(type default)
			)
			(layer "B.SilkS")
		)
		(fp_line
			(start -1.1049 0.724916)
			(end -1.1049 -0.724916)
			(stroke
				(width 0.1)
				(type default)
			)
			(layer "B.Fab")
		)
		(fp_line
			(start 1.1049 0.724916)
			(end -1.1049 0.724916)
			(stroke
				(width 0.1)
				(type default)
			)
			(layer "B.Fab")
		)
		(fp_line
			(start -1.1049 -0.724916)
			(end 1.1049 -0.724916)
			(stroke
				(width 0.1)
				(type default)
			)
			(layer "B.Fab")
		)
		(fp_line
			(start 1.1049 -0.724916)
			(end 1.1049 0.724916)
			(stroke
				(width 0.1)
				(type default)
			)
			(layer "B.Fab")
		)
		(pad "1" smd rect
			(at 0.889 0 270)
			(size 1.016 1.27)
			(layers "B.Cu" "B.Mask" "B.Paste")
			(net "SW_P12V_AUX_PVDDCR_SOC_P1_FLT")
		)
		(pad "2" smd rect
			(at -0.889 0 270)
			(size 1.016 1.27)
			(layers "B.Cu" "B.Mask" "B.Paste")
			(net "GND")
		)
	)
)
